# S9S_MB_2U (Grand Teton) — schematic netlist excerpt (pin names and nets, part order shuffled) for the footprints in the layout excerpt that follows; sources: Cadence DE-HDL packaged netlist, KiCad conversion of 03242023_DA0F0TMBIJ0_F0T_Motherboard_J_brd_V01_OCP.brd

C204  Q_CAP  0.1UF 25V 10% X7R  pkg 0402  page 206 : A = P3V3_DB2000_VDD ; B = GND
R4056  Q_RES  0 5% CHIP  pkg 0402LF  page 215 : A = HSC_D_OC ; B = HSC_D_OC_R1

(kicad_pcb
	(version 20260206)
	(generator "pcbnew")
	(generator_version "10.0")
	(general
		(thickness 1.6)
		(legacy_teardrops no)
	)
	(paper "A4")
	(title_block
		(title "03242023_DA0F0TMBIJ0_F0T_Motherboard_J_brd_V01_OCP.brd")
		(comment 1 "Grand Teton / footprints 5227-5228 of 6105")
	)
	(layers
		(0 "F.Cu" signal "TOP")
		(4 "In1.Cu" signal "GND")
		(6 "In2.Cu" signal "IN1")
		(8 "In3.Cu" signal "GND1")
		(10 "In4.Cu" signal "IN2")
		(12 "In5.Cu" signal "GND2")
		(14 "In6.Cu" signal "IN3")
		(16 "In7.Cu" signal "GND3")
		(18 "In8.Cu" signal "VCC")
		(20 "In9.Cu" signal "VCC1")
		(22 "In10.Cu" signal "GND4")
		(24 "In11.Cu" signal "IN4")
		(26 "In12.Cu" signal "GND5")
		(28 "In13.Cu" signal "IN5")
		(30 "In14.Cu" signal "GND6")
		(32 "In15.Cu" signal "IN6")
		(34 "In16.Cu" signal "GND7")
		(2 "B.Cu" signal "BOTTOM")
		(9 "F.Adhes" user "F.Adhesive")
		(11 "B.Adhes" user "B.Adhesive")
		(13 "F.Paste" user "Package Geometry/Pastemask Top")
		(15 "B.Paste" user "Package Geometry/Pastemask Bottom")
		(5 "F.SilkS" user "Ref Des/Silkscreen Top")
		(7 "B.SilkS" user "Ref Des/Silkscreen Bottom")
		(1 "F.Mask" user "Board Geometry/Soldermask Top")
		(3 "B.Mask" user "Board Geometry/Soldermask Bottom")
		(17 "Dwgs.User" user "User.Drawings")
		(19 "Cmts.User" user "User.Comments")
		(21 "Eco1.User" user "User.Eco1")
		(23 "Eco2.User" user "User.Eco2")
		(25 "Edge.Cuts" user "Board Geometry/Outline")
		(27 "Margin" user)
		(31 "F.CrtYd" user "Package Geometry/Place Bound Top")
		(29 "B.CrtYd" user "Package Geometry/Place Bound Bottom")
		(35 "F.Fab" user "Ref Des/Assembly Top")
		(33 "B.Fab" user "Ref Des/Assembly Bottom")
	)
	(footprint ""
		(layer "B.Cu")
		(at 197.41388 -107.495848)
		(property "Reference" "R4056"
			(at 0 0 0)
			(layer "B.SilkS")
			(hide yes)
			(effects
				(font
					(size 1.27 1.27)
				)
				(justify mirror)
			)
		)
		(property "Value" ""
			(at 0 0 0)
			(layer "B.Fab")
			(effects
				(font
					(size 1.27 1.27)
				)
				(justify mirror)
			)
		)
		(duplicate_pad_numbers_are_jumpers no)
		(fp_line
			(start -0.7874 -0.4064)
			(end -0.7874 0.4064)
			(stroke
				(width 0.1524)
				(type default)
			)
			(layer "B.SilkS")
		)
		(fp_line
			(start -0.7874 0.4064)
			(end 0.7874 0.4064)
			(stroke
				(width 0.1524)
				(type default)
			)
			(layer "B.SilkS")
		)
		(fp_line
			(start 0.7874 -0.4064)
			(end -0.7874 -0.4064)
			(stroke
				(width 0.1524)
				(type default)
			)
			(layer "B.SilkS")
		)
		(fp_line
			(start 0.7874 0.4064)
			(end 0.7874 -0.4064)
			(stroke
				(width 0.1524)
				(type default)
			)
			(layer "B.SilkS")
		)
		(fp_line
			(start -0.67945 -0.3048)
			(end -0.67945 0.3048)
			(stroke
				(width 0.1)
				(type default)
			)
			(layer "B.Fab")
		)
		(fp_line
			(start -0.67945 0.3048)
			(end -0.120396 0.3048)
			(stroke
				(width 0.1)
				(type default)
			)
			(layer "B.Fab")
		)
		(fp_line
			(start -0.12065 -0.3048)
			(end -0.67945 -0.3048)
			(stroke
				(width 0.1)
				(type default)
			)
			(layer "B.Fab")
		)
		(fp_line
			(start -0.12065 -0.2794)
			(end -0.12065 -0.3048)
			(stroke
				(width 0.1)
				(type default)
			)
			(layer "B.Fab")
		)
		(fp_line
			(start -0.120396 0.2794)
			(end 0.12065 0.2794)
			(stroke
				(width 0.1)
				(type default)
			)
			(layer "B.Fab")
		)
		(fp_line
			(start -0.120396 0.3048)
			(end -0.120396 0.2794)
			(stroke
				(width 0.1)
				(type default)
			)
			(layer "B.Fab")
		)
		(fp_line
			(start 0.12065 -0.305054)
			(end 0.12065 -0.2794)
			(stroke
				(width 0.1)
				(type default)
			)
			(layer "B.Fab")
		)
		(fp_line
			(start 0.12065 -0.2794)
			(end -0.12065 -0.2794)
			(stroke
				(width 0.1)
				(type default)
			)
			(layer "B.Fab")
		)
		(fp_line
			(start 0.12065 0.2794)
			(end 0.12065 0.3048)
			(stroke
				(width 0.1)
				(type default)
			)
			(layer "B.Fab")
		)
		(fp_line
			(start 0.12065 0.3048)
			(end 0.67945 0.3048)
			(stroke
				(width 0.1)
				(type default)
			)
			(layer "B.Fab")
		)
		(fp_line
			(start 0.67945 -0.305054)
			(end 0.12065 -0.305054)
			(stroke
				(width 0.1)
				(type default)
			)
			(layer "B.Fab")
		)
		(fp_line
			(start 0.67945 0.3048)
			(end 0.67945 -0.305054)
			(stroke
				(width 0.1)
				(type default)
			)
			(layer "B.Fab")
		)
		(pad "1" smd circle
			(at 0.40005 0 180)
			(size 0 0)
			(layers "B.Cu" "B.Mask" "B.Paste")
			(net "HSC_D_OC")
		)
		(pad "2" smd circle
			(at -0.40005 0 180)
			(size 0 0)
			(layers "B.Cu" "B.Mask" "B.Paste")
			(net "HSC_D_OC_R1")
		)
	)
	(footprint ""
		(layer "B.Cu")
		(at 229.87254 -125.040898 -90)
		(property "Reference" "C204"
			(at 0 0 90)
			(layer "B.SilkS")
			(hide yes)
			(effects
				(font
					(size 1.27 1.27)
				)
				(justify mirror)
			)
		)
		(property "Value" ""
			(at 0 0 90)
			(layer "B.Fab")
			(effects
				(font
					(size 1.27 1.27)
				)
				(justify mirror)
			)
		)
		(duplicate_pad_numbers_are_jumpers no)
		(fp_line
			(start -0.7874 0.4064)
			(end 0.7874 0.4064)
			(stroke
				(width 0.1524)
				(type default)
			)
			(layer "B.SilkS")
		)
		(fp_line
			(start 0.7874 0.4064)
			(end 0.7874 -0.4064)
			(stroke
				(width 0.1524)
				(type default)
			)
			(layer "B.SilkS")
		)
		(fp_line
			(start -0.7874 -0.4064)
			(end -0.7874 0.4064)
			(stroke
				(width 0.1524)
				(type default)
			)
			(layer "B.SilkS")
		)
		(fp_line
			(start 0.7874 -0.4064)
			(end -0.7874 -0.4064)
			(stroke
				(width 0.1524)
				(type default)
			)
			(layer "B.SilkS")
		)
		(fp_line
			(start -0.67945 0.3048)
			(end -0.120396 0.3048)
			(stroke
				(width 0.1)
				(type default)
			)
			(layer "B.Fab")
		)
		(fp_line
			(start -0.120396 0.3048)
			(end -0.120396 0.2794)
			(stroke
				(width 0.1)
				(type default)
			)
			(layer "B.Fab")
		)
		(fp_line
			(start 0.12065 0.3048)
			(end 0.67945 0.3048)
			(stroke
				(width 0.1)
				(type default)
			)
			(layer "B.Fab")
		)
		(fp_line
			(start 0.67945 0.3048)
			(end 0.67945 -0.305054)
			(stroke
				(width 0.1)
				(type default)
			)
			(layer "B.Fab")
		)
		(fp_line
			(start -0.120396 0.2794)
			(end 0.12065 0.2794)
			(stroke
				(width 0.1)
				(type default)
			)
			(layer "B.Fab")
		)
		(fp_line
			(start 0.12065 0.2794)
			(end 0.12065 0.3048)
			(stroke
				(width 0.1)
				(type default)
			)
			(layer "B.Fab")
		)
		(fp_line
			(start -0.12065 -0.2794)
			(end -0.12065 -0.3048)
			(stroke
				(width 0.1)
				(type default)
			)
			(layer "B.Fab")
		)
		(fp_line
			(start 0.12065 -0.2794)
			(end -0.12065 -0.2794)
			(stroke
				(width 0.1)
				(type default)
			)
			(layer "B.Fab")
		)
		(fp_line
			(start -0.67945 -0.3048)
			(end -0.67945 0.3048)
			(stroke
				(width 0.1)
				(type default)
			)
			(layer "B.Fab")
		)
		(fp_line
			(start -0.12065 -0.3048)
			(end -0.67945 -0.3048)
			(stroke
				(width 0.1)
				(type default)
			)
			(layer "B.Fab")
		)
		(fp_line
			(start 0.12065 -0.305054)
			(end 0.12065 -0.2794)
			(stroke
				(width 0.1)
				(type default)
			)
			(layer "B.Fab")
		)
		(fp_line
			(start 0.67945 -0.305054)
			(end 0.12065 -0.305054)
			(stroke
				(width 0.1)
				(type default)
			)
			(layer "B.Fab")
		)
		(pad "1" smd circle
			(at 0.40005 0 90)
			(size 0 0)
			(layers "B.Cu" "B.Mask" "B.Paste")
			(net "P3V3_DB2000_VDD")
		)
		(pad "2" smd circle
			(at -0.40005 0 90)
			(size 0 0)
			(layers "B.Cu" "B.Mask" "B.Paste")
			(net "GND")
		)
	)
)
